(kicad_pcb
	(version 20260206)
	(generator "pcbnew")
	(generator_version "10.0")
	(general
		(thickness 1.21888)
		(legacy_teardrops no)
	)
	(paper "A4")
	(title_block
		(title "timecard-v9 — TimeCard-DC-V9_EXP.PcbDoc")
		(comment 1 "Time Appliance Project (Time Card) / footprints 389-400 of 402")
	)
	(layers
		(0 "F.Cu" signal "TOP")
		(4 "In1.Cu" signal "SGND")
		(6 "In2.Cu" signal "IN1")
		(8 "In3.Cu" signal "IN2")
		(10 "In4.Cu" signal "SGND1")
		(2 "B.Cu" signal "BOTTOM")
		(9 "F.Adhes" user "F.Adhesive")
		(11 "B.Adhes" user "B.Adhesive")
		(13 "F.Paste" user "Top Paste")
		(15 "B.Paste" user "Bottom Paste")
		(5 "F.SilkS" user "Top Overlay")
		(7 "B.SilkS" user "Bottom Overlay")
		(1 "F.Mask" user "Top Solder")
		(3 "B.Mask" user "Bottom Solder")
		(17 "Dwgs.User" user "User.Drawings")
		(19 "Cmts.User" user "User.Comments")
		(21 "Eco1.User" user "User.Eco1")
		(23 "Eco2.User" user "User.Eco2")
		(25 "Edge.Cuts" user)
		(27 "Margin" user)
		(31 "F.CrtYd" user "Top Courtyard")
		(29 "B.CrtYd" user "Bottom Courtyard")
		(35 "F.Fab" user "Top Component Center")
		(33 "B.Fab" user "Bottom Component Center")
	)
	(footprint "Vault:FP-0402-L_1_0_1-W_0_5_0_1-IPC_C"
		(layer "B.Cu")
		(at 112.4216 80.51363 90)
		(property "Reference" "C33"
			(at 1.96883 -0.273079 90)
			(unlocked yes)
			(layer "B.SilkS")
			(effects
				(font
					(size 0.762 0.762)
					(thickness 0.2286)
				)
				(justify mirror)
			)
		)
		(property "Value" "0.1uF_25V_0402"
			(at 2.069035 -2.567191 270)
			(unlocked yes)
			(layer "B.SilkS")
			(hide yes)
			(effects
				(font
					(size 0.762 0.762)
					(thickness 0.2286)
				)
				(justify mirror)
			)
		)
		(sheetname "05-GPS_IMU_SENSORS")
		(sheetfile "05-GPS_IMU_SENSORS.kicad_sch")
		(duplicate_pad_numbers_are_jumpers no)
		(fp_line
			(start -0.65606 -0.7)
			(end 0.65607 -0.7)
			(stroke
				(width 0.2)
				(type solid)
			)
			(layer "B.SilkS")
		)
		(fp_line
			(start -0.65606 0.7)
			(end 0.65607 0.7)
			(stroke
				(width 0.2)
				(type solid)
			)
			(layer "B.SilkS")
		)
		(fp_line
			(start 0.75607 -0.4)
			(end 0.75607 0.4)
			(stroke
				(width 0.2)
				(type solid)
			)
			(layer "B.CrtYd")
		)
		(fp_line
			(start -0.75606 -0.4)
			(end 0.75607 -0.4)
			(stroke
				(width 0.2)
				(type solid)
			)
			(layer "B.CrtYd")
		)
		(fp_line
			(start -0.75606 -0.4)
			(end -0.75606 0.4)
			(stroke
				(width 0.2)
				(type solid)
			)
			(layer "B.CrtYd")
		)
		(fp_line
			(start -0.75606 0.4)
			(end 0.75607 0.4)
			(stroke
				(width 0.2)
				(type solid)
			)
			(layer "B.CrtYd")
		)
		(fp_line
			(start 0 -0.5)
			(end 0 0.5)
			(stroke
				(width 0.1)
				(type solid)
			)
			(layer "B.Fab")
		)
		(fp_line
			(start 0.75607 -0.4)
			(end 0.75607 0.4)
			(stroke
				(width 0.2)
				(type solid)
			)
			(layer "B.Fab")
		)
		(fp_line
			(start -0.75606 -0.4)
			(end 0.75607 -0.4)
			(stroke
				(width 0.2)
				(type solid)
			)
			(layer "B.Fab")
		)
		(fp_line
			(start -0.75606 -0.4)
			(end -0.75606 0.4)
			(stroke
				(width 0.2)
				(type solid)
			)
			(layer "B.Fab")
		)
		(fp_line
			(start -0.5 0)
			(end 0.5 0)
			(stroke
				(width 0.1)
				(type solid)
			)
			(layer "B.Fab")
		)
		(fp_line
			(start -0.75606 0.4)
			(end 0.75607 0.4)
			(stroke
				(width 0.2)
				(type solid)
			)
			(layer "B.Fab")
		)
		(fp_text user "${REFERENCE}"
			(at -0.00001 -0.09602 270)
			(unlocked yes)
			(layer "B.Fab")
			(effects
				(font
					(face "Arial")
					(size 0.63 0.63)
					(thickness 0.1)
				)
				(justify left bottom mirror)
			)
		)
		(pad "1" smd rect
			(at -0.36553 0 90)
			(size 0.58106 0.51213)
			(layers "B.Cu" "B.Mask" "B.Paste")
			(net "BNO_P3V3")
			(solder_mask_margin 0)
			(solder_paste_margin 0)
		)
		(pad "2" smd rect
			(at 0.36554 0 90)
			(size 0.58106 0.51213)
			(layers "B.Cu" "B.Mask" "B.Paste")
			(net "GND")
			(solder_mask_margin 0)
			(solder_paste_margin 0)
		)
	)
	(footprint "Vault:CAPC1005X55X25LL05T10"
		(layer "B.Cu")
		(at 225.2116 116.83603 180)
		(property "Reference" "C88"
			(at -0.1386 -1.253239 180)
			(unlocked yes)
			(layer "B.SilkS")
			(effects
				(font
					(size 0.762 0.762)
					(thickness 0.2286)
				)
				(justify mirror)
			)
		)
		(property "Value" "47pF_50V_0402"
			(at -2.656031 -9.61078 90)
			(unlocked yes)
			(layer "B.SilkS")
			(hide yes)
			(effects
				(font
					(size 0.762 0.762)
					(thickness 0.2286)
				)
				(justify mirror)
			)
		)
		(sheetname "09-USBUart_PPSMUX_UARTMUX")
		(sheetfile "09-USBUart_PPSMUX_UARTMUX.kicad_sch")
		(duplicate_pad_numbers_are_jumpers no)
		(pad "1" smd rect
			(at -0.39 0 90)
			(size 0.52 0.56)
			(layers "B.Cu" "B.Mask" "B.Paste")
			(net "GND")
		)
		(pad "2" smd rect
			(at 0.39 0 90)
			(size 0.52 0.56)
			(layers "B.Cu" "B.Mask" "B.Paste")
			(net "FTDI_USB_R_N")
		)
	)
	(footprint "Vault:RESC1608X55X25LL10T15"
		(layer "B.Cu")
		(at 129.4216 88.8162)
		(property "Reference" "R10"
			(at -0.2286 -1.273069 0)
			(unlocked yes)
			(layer "B.SilkS")
			(effects
				(font
					(size 0.762 0.762)
					(thickness 0.2286)
				)
				(justify mirror)
			)
		)
		(property "Value" "4.7K"
			(at -2.630671 -2.57724 270)
			(unlocked yes)
			(layer "B.SilkS")
			(hide yes)
			(effects
				(font
					(size 0.762 0.762)
					(thickness 0.2286)
				)
				(justify mirror)
			)
		)
		(sheetname "06-MAC")
		(sheetfile "06-MAC.kicad_sch")
		(duplicate_pad_numbers_are_jumpers no)
		(pad "1" smd rect
			(at -0.65 0 270)
			(size 0.8 0.6)
			(layers "B.Cu" "B.Mask" "B.Paste")
			(net "GND")
		)
		(pad "2" smd rect
			(at 0.65 0 270)
			(size 0.8 0.6)
			(layers "B.Cu" "B.Mask" "B.Paste")
			(net "FPGA_MAC_PPS_IN1-")
		)
	)
	(footprint "Vault:RESC1608X55X30LL15T20"
		(layer "B.Cu")
		(at 181.90985 106.4162 90)
		(property "Reference" "R37"
			(at 2.1714 0.164521 90)
			(unlocked yes)
			(layer "B.SilkS")
			(effects
				(font
					(size 0.762 0.762)
					(thickness 0.2286)
				)
				(justify mirror)
			)
		)
		(property "Value" "10K"
			(at -2.630671 -1.76469 0)
			(unlocked yes)
			(layer "B.SilkS")
			(hide yes)
			(effects
				(font
					(size 0.762 0.762)
					(thickness 0.2286)
				)
				(justify mirror)
			)
		)
		(sheetname "05-GPS_IMU_SENSORS")
		(sheetfile "05-GPS_IMU_SENSORS.kicad_sch")
		(duplicate_pad_numbers_are_jumpers no)
		(pad "1" smd rect
			(at -0.575 0)
			(size 0.85 0.75)
			(layers "B.Cu" "B.Mask" "B.Paste")
			(net "EXT_EEPROM_WP")
		)
		(pad "2" smd rect
			(at 0.575 0)
			(size 0.85 0.75)
			(layers "B.Cu" "B.Mask" "B.Paste")
			(net "+3.3V")
		)
	)
	(footprint "Vault:RESC1608X55X30NL15T15"
		(layer "B.Cu")
		(at 79.4216 52.7162 180)
		(property "Reference" "R36"
			(at -2.9714 -0.126921 0)
			(unlocked yes)
			(layer "B.SilkS")
			(effects
				(font
					(size 0.762 0.762)
					(thickness 0.2286)
				)
				(justify mirror)
			)
		)
		(property "Value" "200 OHM"
			(at -2.935471 -4.78626 90)
			(unlocked yes)
			(layer "B.SilkS")
			(hide yes)
			(effects
				(font
					(size 0.762 0.762)
					(thickness 0.2286)
				)
				(justify mirror)
			)
		)
		(sheetname "02-USER_IO_STATUS")
		(sheetfile "02-USER_IO_STATUS.kicad_sch")
		(duplicate_pad_numbers_are_jumpers no)
		(pad "1" smd rect
			(at -0.675 0 90)
			(size 0.95 0.8)
			(layers "B.Cu" "B.Mask" "B.Paste")
			(net "LED2")
		)
		(pad "2" smd rect
			(at 0.675 0 90)
			(size 0.95 0.8)
			(layers "B.Cu" "B.Mask" "B.Paste")
			(net "NetD9_1")
		)
	)
	(footprint "Vault:FP-RG1005-IPC_A"
		(layer "B.Cu")
		(at 181.3216 88.8162 180)
		(property "Reference" "R63"
			(at 0.2286 1.573079 0)
			(unlocked yes)
			(layer "B.SilkS")
			(effects
				(font
					(size 0.762 0.762)
					(thickness 0.2286)
				)
				(justify mirror)
			)
		)
		(property "Value" "22_0.5%_0402"
			(at -2.884671 -8.036475 90)
			(unlocked yes)
			(layer "B.SilkS")
			(hide yes)
			(effects
				(font
					(size 0.762 0.762)
					(thickness 0.2286)
				)
				(justify mirror)
			)
		)
		(sheetname "03-POWER")
		(sheetfile "03-POWER.kicad_sch")
		(duplicate_pad_numbers_are_jumpers no)
		(fp_line
			(start 0.85792 0.73624)
			(end -0.85791 0.73624)
			(stroke
				(width 0.2)
				(type solid)
			)
			(layer "B.SilkS")
		)
		(fp_line
			(start 0.85792 -0.73624)
			(end -0.85791 -0.73624)
			(stroke
				(width 0.2)
				(type solid)
			)
			(layer "B.SilkS")
		)
		(fp_line
			(start 1.05792 0.53624)
			(end -1.05791 0.53624)
			(stroke
				(width 0.2)
				(type solid)
			)
			(layer "B.CrtYd")
		)
		(fp_line
			(start 1.05792 -0.53624)
			(end 1.05792 0.53624)
			(stroke
				(width 0.2)
				(type solid)
			)
			(layer "B.CrtYd")
		)
		(fp_line
			(start 1.05792 -0.53624)
			(end -1.05791 -0.53624)
			(stroke
				(width 0.2)
				(type solid)
			)
			(layer "B.CrtYd")
		)
		(fp_line
			(start -1.05791 -0.53624)
			(end -1.05791 0.53624)
			(stroke
				(width 0.2)
				(type solid)
			)
			(layer "B.CrtYd")
		)
		(fp_line
			(start 1.05792 0.53624)
			(end -1.05791 0.53624)
			(stroke
				(width 0.2)
				(type solid)
			)
			(layer "B.Fab")
		)
		(fp_line
			(start 1.05792 -0.53624)
			(end 1.05792 0.53624)
			(stroke
				(width 0.2)
				(type solid)
			)
			(layer "B.Fab")
		)
		(fp_line
			(start 1.05792 -0.53624)
			(end -1.05791 -0.53624)
			(stroke
				(width 0.2)
				(type solid)
			)
			(layer "B.Fab")
		)
		(fp_line
			(start 0.5 0)
			(end -0.5 0)
			(stroke
				(width 0.1)
				(type solid)
			)
			(layer "B.Fab")
		)
		(fp_line
			(start 0 -0.5)
			(end 0 0.5)
			(stroke
				(width 0.1)
				(type solid)
			)
			(layer "B.Fab")
		)
		(fp_line
			(start -1.05791 -0.53624)
			(end -1.05791 0.53624)
			(stroke
				(width 0.2)
				(type solid)
			)
			(layer "B.Fab")
		)
		(fp_text user "${REFERENCE}"
			(at -0.00001 -0.09602 360)
			(unlocked yes)
			(layer "B.Fab")
			(effects
				(font
					(face "Arial")
					(size 0.63 0.63)
					(thickness 0.1)
				)
				(justify left bottom mirror)
			)
		)
		(pad "1" smd rect
			(at -0.51351 0 180)
			(size 0.68881 0.67248)
			(layers "B.Cu" "B.Mask" "B.Paste")
			(net "GND")
			(solder_mask_margin 0)
			(solder_paste_margin 0)
		)
		(pad "2" smd rect
			(at 0.51351 0 180)
			(size 0.68881 0.67248)
			(layers "B.Cu" "B.Mask" "B.Paste")
			(net "NetR61_1")
			(solder_mask_margin 0)
			(solder_paste_margin 0)
		)
	)
	(footprint "Vault:CAPC1005X56X25NL10T15"
		(layer "B.Cu")
		(at 87.1116 69.33347 -90)
		(property "Reference" "C21"
			(at 0.78661 1.556325 270)
			(unlocked yes)
			(layer "B.SilkS")
			(effects
				(font
					(size 0.762 0.762)
					(thickness 0.2286)
				)
				(justify left bottom mirror)
			)
		)
		(property "Value" "0.1uF_25V_0402"
			(at -9.460165 23.8395 0)
			(unlocked yes)
			(layer "B.SilkS")
			(hide yes)
			(effects
				(font
					(size 0.762 0.762)
					(thickness 0.2286)
				)
				(justify left bottom mirror)
			)
		)
		(sheetname "03-POWER")
		(sheetfile "03-POWER.kicad_sch")
		(duplicate_pad_numbers_are_jumpers no)
		(pad "1" smd rect
			(at -0.44 0 180)
			(size 0.64 0.68)
			(layers "B.Cu" "B.Mask" "B.Paste")
			(net "GND")
		)
		(pad "2" smd rect
			(at 0.44 0 180)
			(size 0.64 0.68)
			(layers "B.Cu" "B.Mask" "B.Paste")
			(net "+3.3V")
		)
	)
	(footprint "Vault:CAPC1608X87X45ML20T05"
		(layer "B.Cu")
		(at 102.7491 67.15612)
		(property "Reference" "C54"
			(at 0.2011 1.333159 180)
			(unlocked yes)
			(layer "B.SilkS")
			(effects
				(font
					(size 0.762 0.762)
					(thickness 0.2286)
				)
				(justify mirror)
			)
		)
		(property "Value" "0.1uF"
			(at 2.069035 -2.630671 180)
			(unlocked yes)
			(layer "B.SilkS")
			(hide yes)
			(effects
				(font
					(size 0.762 0.762)
					(thickness 0.2286)
				)
				(justify mirror)
			)
		)
		(sheetname "05-GPS_IMU_SENSORS")
		(sheetfile "05-GPS_IMU_SENSORS.kicad_sch")
		(duplicate_pad_numbers_are_jumpers no)
		(pad "1" smd rect
			(at -0.7 0 270)
			(size 1.1 1.05)
			(layers "B.Cu" "B.Mask" "B.Paste")
			(net "GND")
		)
		(pad "2" smd rect
			(at 0.7 0 270)
			(size 1.1 1.05)
			(layers "B.Cu" "B.Mask" "B.Paste")
			(net "+5.0V")
		)
	)
	(footprint "Vault:CAPC1608X87X45ML20T05"
		(layer "B.Cu")
		(at 113.5216 66.7162 90)
		(property "Reference" "C43"
			(at 0.2286 1.473069 270)
			(unlocked yes)
			(layer "B.SilkS")
			(effects
				(font
					(size 0.762 0.762)
					(thickness 0.2286)
				)
				(justify mirror)
			)
		)
		(property "Value" "0.1uF"
			(at 2.069035 -2.630671 270)
			(unlocked yes)
			(layer "B.SilkS")
			(hide yes)
			(effects
				(font
					(size 0.762 0.762)
					(thickness 0.2286)
				)
				(justify mirror)
			)
		)
		(sheetname "05-GPS_IMU_SENSORS")
		(sheetfile "05-GPS_IMU_SENSORS.kicad_sch")
		(duplicate_pad_numbers_are_jumpers no)
		(pad "1" smd rect
			(at -0.7 0)
			(size 1.1 1.05)
			(layers "B.Cu" "B.Mask" "B.Paste")
			(net "GND")
		)
		(pad "2" smd rect
			(at 0.7 0)
			(size 1.1 1.05)
			(layers "B.Cu" "B.Mask" "B.Paste")
			(net "+3.3V")
		)
	)
	(footprint "Vault:FP-0402-L_1_0_1-W_0_5_0_1-IPC_C"
		(layer "B.Cu")
		(at 124.07407 74.1662 -90)
		(property "Reference" "C99"
			(at 2.5532 0.325539 90)
			(unlocked yes)
			(layer "B.SilkS")
			(effects
				(font
					(size 0.762 0.762)
					(thickness 0.2032)
				)
				(justify mirror)
			)
		)
		(property "Value" "0.1uF_25V_0402"
			(at -2.465551 -9.813805 180)
			(unlocked yes)
			(layer "B.SilkS")
			(hide yes)
			(effects
				(font
					(size 0.762 0.762)
					(thickness 0.2032)
				)
				(justify mirror)
			)
		)
		(sheetname "10-M2_GPS")
		(sheetfile "10-M2_GPS.kicad_sch")
		(duplicate_pad_numbers_are_jumpers no)
		(fp_line
			(start 0.65607 0.70001)
			(end -0.65607 0.70001)
			(stroke
				(width 0.2)
				(type solid)
			)
			(layer "B.SilkS")
		)
		(fp_line
			(start 0.65607 -0.7)
			(end -0.65607 -0.7)
			(stroke
				(width 0.2)
				(type solid)
			)
			(layer "B.SilkS")
		)
		(fp_line
			(start -0.75607 0.4)
			(end -0.75607 -0.39999)
			(stroke
				(width 0.2)
				(type solid)
			)
			(layer "B.CrtYd")
		)
		(fp_line
			(start 0.75607 0.4)
			(end -0.75607 0.4)
			(stroke
				(width 0.2)
				(type solid)
			)
			(layer "B.CrtYd")
		)
		(fp_line
			(start 0.75607 0.4)
			(end 0.75607 -0.39999)
			(stroke
				(width 0.2)
				(type solid)
			)
			(layer "B.CrtYd")
		)
		(fp_line
			(start 0.75607 -0.39999)
			(end -0.75607 -0.39999)
			(stroke
				(width 0.2)
				(type solid)
			)
			(layer "B.CrtYd")
		)
		(fp_line
			(start 0 0.5)
			(end 0 -0.49999)
			(stroke
				(width 0.1)
				(type solid)
			)
			(layer "B.Fab")
		)
		(fp_line
			(start -0.75607 0.4)
			(end -0.75607 -0.39999)
			(stroke
				(width 0.2)
				(type solid)
			)
			(layer "B.Fab")
		)
		(fp_line
			(start 0.75607 0.4)
			(end -0.75607 0.4)
			(stroke
				(width 0.2)
				(type solid)
			)
			(layer "B.Fab")
		)
		(fp_line
			(start 0.75607 0.4)
			(end 0.75607 -0.39999)
			(stroke
				(width 0.2)
				(type solid)
			)
			(layer "B.Fab")
		)
		(fp_line
			(start 0.5 0)
			(end -0.5 0)
			(stroke
				(width 0.1)
				(type solid)
			)
			(layer "B.Fab")
		)
		(fp_line
			(start 0.75607 -0.39999)
			(end -0.75607 -0.39999)
			(stroke
				(width 0.2)
				(type solid)
			)
			(layer "B.Fab")
		)
		(fp_text user "${REFERENCE}"
			(at -0.00001 -0.09601 90)
			(unlocked yes)
			(layer "B.Fab")
			(effects
				(font
					(face "Arial")
					(size 0.63 0.63)
					(thickness 0.1)
				)
				(justify left bottom mirror)
			)
		)
		(pad "1" smd rect
			(at -0.36554 0 270)
			(size 0.58106 0.51213)
			(layers "B.Cu" "B.Mask" "B.Paste")
			(net "+3.3V")
			(solder_mask_margin 0)
			(solder_paste_margin 0)
		)
		(pad "2" smd rect
			(at 0.36554 0 270)
			(size 0.58106 0.51213)
			(layers "B.Cu" "B.Mask" "B.Paste")
			(net "GND")
			(solder_mask_margin 0)
			(solder_paste_margin 0)
		)
	)
	(footprint "Vault:RESC1609X50X30NL10T20"
		(layer "B.Cu")
		(at 123.3216 88.3162)
		(property "Reference" "R12"
			(at -0.2286 -1.273079 0)
			(unlocked yes)
			(layer "B.SilkS")
			(effects
				(font
					(size 0.762 0.762)
					(thickness 0.2286)
				)
				(justify mirror)
			)
		)
		(property "Value" "110R"
			(at -2.884681 -2.24708 270)
			(unlocked yes)
			(layer "B.SilkS")
			(hide yes)
			(effects
				(font
					(size 0.762 0.762)
					(thickness 0.2286)
				)
				(justify mirror)
			)
		)
		(sheetname "06-MAC")
		(sheetfile "06-MAC.kicad_sch")
		(duplicate_pad_numbers_are_jumpers no)
		(pad "1" smd rect
			(at -0.625 0 270)
			(size 0.95 0.8)
			(layers "B.Cu" "B.Mask" "B.Paste")
			(net "MAC_PPS_OUT-")
		)
		(pad "2" smd rect
			(at 0.625 0 270)
			(size 0.95 0.8)
			(layers "B.Cu" "B.Mask" "B.Paste")
			(net "MAC_PPS_OUT+")
		)
	)
	(footprint "Vault:RESC1005X40X25NL10T10"
		(layer "B.Cu")
		(at 184.8216 94.3162)
		(property "Reference" "R185"
			(at 2.396998 -2.70424 270)
			(unlocked yes)
			(layer "B.SilkS")
			(effects
				(font
					(size 1.524 1.524)
					(thickness 0.254)
				)
				(justify mirror)
			)
		)
		(property "Value" "10K_1%_0402"
			(at -2.759202 -8.036515 270)
			(unlocked yes)
			(layer "B.SilkS")
			(hide yes)
			(effects
				(font
					(size 1.524 1.524)
					(thickness 0.254)
				)
				(justify mirror)
			)
		)
		(sheetname "03-POWER")
		(sheetfile "03-POWER.kicad_sch")
		(duplicate_pad_numbers_are_jumpers no)
		(pad "1" smd rect
			(at -0.425 0 270)
			(size 0.6 0.65)
			(layers "B.Cu" "B.Mask" "B.Paste")
			(net "GND")
		)
		(pad "2" smd rect
			(at 0.425 0 270)
			(size 0.6 0.65)
			(layers "B.Cu" "B.Mask" "B.Paste")
			(net "NetR129_2")
		)
	)
)
